(kicad_pcb
	(version 20260206)
	(generator "pcbnew")
	(generator_version "10.0")
	(general
		(thickness 1.6)
		(legacy_teardrops no)
	)
	(paper "A4")
	(title_block
		(title "04192023_DAF0TMB3IC0_F0TG_MB_C_brd_V02_OCP.brd")
		(comment 1 "Grand Teton / footprints 1809-1815 of 8354")
	)
	(layers
		(0 "F.Cu" signal "TOP")
		(4 "In1.Cu" signal "GND")
		(6 "In2.Cu" signal "IN1")
		(8 "In3.Cu" signal "GND1")
		(10 "In4.Cu" signal "IN2")
		(12 "In5.Cu" signal "GND2")
		(14 "In6.Cu" signal "IN3")
		(16 "In7.Cu" signal "GND3")
		(18 "In8.Cu" signal "VCC")
		(20 "In9.Cu" signal "VCC1")
		(22 "In10.Cu" signal "GND4")
		(24 "In11.Cu" signal "IN4")
		(26 "In12.Cu" signal "GND5")
		(28 "In13.Cu" signal "IN5")
		(30 "In14.Cu" signal "GND6")
		(32 "In15.Cu" signal "IN6")
		(34 "In16.Cu" signal "GND7")
		(2 "B.Cu" signal "BOTTOM")
		(9 "F.Adhes" user "F.Adhesive")
		(11 "B.Adhes" user "B.Adhesive")
		(13 "F.Paste" user "Package Geometry/Pastemask Top")
		(15 "B.Paste" user "Package Geometry/Pastemask Bottom")
		(5 "F.SilkS" user "Ref Des/Silkscreen Top")
		(7 "B.SilkS" user "Ref Des/Silkscreen Bottom")
		(1 "F.Mask" user "Board Geometry/Soldermask Top")
		(3 "B.Mask" user "Board Geometry/Soldermask Bottom")
		(17 "Dwgs.User" user "User.Drawings")
		(19 "Cmts.User" user "User.Comments")
		(21 "Eco1.User" user "User.Eco1")
		(23 "Eco2.User" user "User.Eco2")
		(25 "Edge.Cuts" user "Board Geometry/Outline")
		(27 "Margin" user)
		(31 "F.CrtYd" user "Package Geometry/Place Bound Top")
		(29 "B.CrtYd" user "Package Geometry/Place Bound Bottom")
		(35 "F.Fab" user "Ref Des/Assembly Top")
		(33 "B.Fab" user "Ref Des/Assembly Bottom")
	)
	(footprint ""
		(layer "F.Cu")
		(at 440.93003 -395.699234 90)
		(property "Reference" "PR6555"
			(at 0 0 90)
			(layer "F.SilkS")
			(hide yes)
			(effects
				(font
					(size 1.27 1.27)
				)
			)
		)
		(property "Value" ""
			(at 0 0 90)
			(layer "F.Fab")
			(effects
				(font
					(size 1.27 1.27)
				)
			)
		)
		(duplicate_pad_numbers_are_jumpers no)
		(fp_line
			(start 0.7874 -0.4064)
			(end 0.7874 0.4064)
			(stroke
				(width 0.1524)
				(type default)
			)
			(layer "F.SilkS")
		)
		(fp_line
			(start -0.7874 -0.4064)
			(end 0.7874 -0.4064)
			(stroke
				(width 0.1524)
				(type default)
			)
			(layer "F.SilkS")
		)
		(fp_line
			(start 0.7874 0.4064)
			(end -0.7874 0.4064)
			(stroke
				(width 0.1524)
				(type default)
			)
			(layer "F.SilkS")
		)
		(fp_line
			(start -0.7874 0.4064)
			(end -0.7874 -0.4064)
			(stroke
				(width 0.1524)
				(type default)
			)
			(layer "F.SilkS")
		)
		(fp_line
			(start -0.12065 -0.305054)
			(end -0.12065 -0.2794)
			(stroke
				(width 0.1)
				(type default)
			)
			(layer "F.Fab")
		)
		(fp_line
			(start -0.67945 -0.305054)
			(end -0.12065 -0.305054)
			(stroke
				(width 0.1)
				(type default)
			)
			(layer "F.Fab")
		)
		(fp_line
			(start 0.67945 -0.3048)
			(end 0.67945 0.3048)
			(stroke
				(width 0.1)
				(type default)
			)
			(layer "F.Fab")
		)
		(fp_line
			(start 0.12065 -0.3048)
			(end 0.67945 -0.3048)
			(stroke
				(width 0.1)
				(type default)
			)
			(layer "F.Fab")
		)
		(fp_line
			(start 0.12065 -0.2794)
			(end 0.12065 -0.3048)
			(stroke
				(width 0.1)
				(type default)
			)
			(layer "F.Fab")
		)
		(fp_line
			(start -0.12065 -0.2794)
			(end 0.12065 -0.2794)
			(stroke
				(width 0.1)
				(type default)
			)
			(layer "F.Fab")
		)
		(fp_line
			(start 0.120396 0.2794)
			(end -0.12065 0.2794)
			(stroke
				(width 0.1)
				(type default)
			)
			(layer "F.Fab")
		)
		(fp_line
			(start -0.12065 0.2794)
			(end -0.12065 0.3048)
			(stroke
				(width 0.1)
				(type default)
			)
			(layer "F.Fab")
		)
		(fp_line
			(start 0.67945 0.3048)
			(end 0.120396 0.3048)
			(stroke
				(width 0.1)
				(type default)
			)
			(layer "F.Fab")
		)
		(fp_line
			(start 0.120396 0.3048)
			(end 0.120396 0.2794)
			(stroke
				(width 0.1)
				(type default)
			)
			(layer "F.Fab")
		)
		(fp_line
			(start -0.12065 0.3048)
			(end -0.67945 0.3048)
			(stroke
				(width 0.1)
				(type default)
			)
			(layer "F.Fab")
		)
		(fp_line
			(start -0.67945 0.3048)
			(end -0.67945 -0.305054)
			(stroke
				(width 0.1)
				(type default)
			)
			(layer "F.Fab")
		)
		(pad "1" smd circle
			(at -0.40005 0 90)
			(size 0 0)
			(layers "F.Cu" "F.Mask" "F.Paste")
			(net "SW_P0V9_RETIMER_CPU0_SW1_RC")
		)
		(pad "2" smd circle
			(at 0.40005 0 90)
			(size 0 0)
			(layers "F.Cu" "F.Mask" "F.Paste")
			(net "GND")
		)
	)
	(footprint ""
		(layer "F.Cu")
		(at 520.044426 -142.882874 90)
		(property "Reference" "X8007"
			(at -2.028444 2.042922 0)
			(unlocked yes)
			(layer "F.SilkS")
			(effects
				(font
					(size 0.7874 0.5842)
					(thickness 0.1524)
				)
				(justify left)
			)
		)
		(property "Value" ""
			(at 0 0 90)
			(layer "F.Fab")
			(effects
				(font
					(size 1.27 1.27)
				)
			)
		)
		(property "Device Type" "TP_TDR_4P_FTS_TH-TP_TDR_4P_DIP,EMPTY,TP15"
			(at 1.30175 1.27 180)
			(unlocked yes)
			(layer "F.Fab")
			(hide yes)
			(effects
				(font
					(size 0.635 0.4064)
					(thickness 0.1524)
				)
			)
		)
		(property "User Part Number" "N_A"
			(at 1.30175 1.27 180)
			(unlocked yes)
			(layer "Cmts.User")
			(hide yes)
			(effects
				(font
					(size 0.635 0.4064)
					(thickness 0.1524)
				)
			)
		)
		(duplicate_pad_numbers_are_jumpers no)
		(fp_line
			(start 2.54 -1.27)
			(end 0 -1.27)
			(stroke
				(width 0.1524)
				(type default)
			)
			(layer "F.SilkS")
		)
		(fp_line
			(start 0 -1.27)
			(end 0 -0.635)
			(stroke
				(width 0.1524)
				(type default)
			)
			(layer "F.SilkS")
		)
		(fp_line
			(start 2.54 -1.1303)
			(end 2.54 -1.27)
			(stroke
				(width 0.1524)
				(type default)
			)
			(layer "F.SilkS")
		)
		(fp_line
			(start 0 0.635)
			(end 0 1.905)
			(stroke
				(width 0.1524)
				(type default)
			)
			(layer "F.SilkS")
		)
		(fp_line
			(start 2.54 1.4097)
			(end 2.54 1.1303)
			(stroke
				(width 0.1524)
				(type default)
			)
			(layer "F.SilkS")
		)
		(fp_line
			(start 0 3.175)
			(end 0 3.81)
			(stroke
				(width 0.1524)
				(type default)
			)
			(layer "F.SilkS")
		)
		(fp_line
			(start 2.54 3.81)
			(end 2.54 3.6703)
			(stroke
				(width 0.1524)
				(type default)
			)
			(layer "F.SilkS")
		)
		(fp_line
			(start 0 3.81)
			(end 2.54 3.81)
			(stroke
				(width 0.1524)
				(type default)
			)
			(layer "F.SilkS")
		)
		(fp_poly
			(pts
				(xy -2.285746 -0.762) (xy -0.761746 0) (xy -2.285746 0.762)
			)
			(stroke
				(width 0)
				(type default)
			)
			(fill yes)
			(layer "F.SilkS")
		)
		(fp_line
			(start 2.54 -1.27)
			(end 0 -1.27)
			(stroke
				(width 0.1)
				(type default)
			)
			(layer "F.Fab")
		)
		(fp_line
			(start 0 -1.27)
			(end 0 3.81)
			(stroke
				(width 0.1)
				(type default)
			)
			(layer "F.Fab")
		)
		(fp_line
			(start 2.54 3.81)
			(end 2.54 -1.27)
			(stroke
				(width 0.1)
				(type default)
			)
			(layer "F.Fab")
		)
		(fp_line
			(start 0 3.81)
			(end 2.54 3.81)
			(stroke
				(width 0.1)
				(type default)
			)
			(layer "F.Fab")
		)
		(fp_poly
			(pts
				(xy -0.761746 0) (xy -2.285746 -0.762) (xy -2.285746 0.762)
			)
			(stroke
				(width 0)
				(type default)
			)
			(fill yes)
			(layer "F.Fab")
		)
		(pad "1" thru_hole circle
			(at 0 0 90)
			(size 1.0033 1.0033)
			(drill 0.249936)
			(layers "*.Cu" "*.Mask")
			(remove_unused_layers no)
			(net "TDR_DIFF_85_TOP_DN")
			(clearance 0.10795)
			(thermal_gap 0.10795)
			(padstack
				(mode front_inner_back)
				(layer "Inner"
					(shape circle)
					(size 0.8001 0.8001)
					(clearance 0.1524)
				)
				(layer "B.Cu"
					(shape circle)
					(size 1.0033 1.0033)
					(clearance 0.10795)
				)
			)
		)
		(pad "2" thru_hole circle
			(at 2.54 0 90)
			(size 1.9939 1.9939)
			(drill 0.249936)
			(layers "*.Cu" "*.Mask")
			(remove_unused_layers no)
			(net "T1_GND")
			(clearance 0.10795)
			(thermal_gap 0.10795)
			(padstack
				(mode front_inner_back)
				(layer "Inner"
					(shape circle)
					(size 0.8001 0.8001)
					(clearance 0.1524)
				)
				(layer "B.Cu"
					(shape circle)
					(size 1.9939 1.9939)
					(clearance 0.10795)
				)
			)
		)
		(pad "3" thru_hole circle
			(at 2.54 2.54 90)
			(size 1.9939 1.9939)
			(drill 0.249936)
			(layers "*.Cu" "*.Mask")
			(remove_unused_layers no)
			(net "T1_GND")
			(clearance 0.10795)
			(thermal_gap 0.10795)
			(padstack
				(mode front_inner_back)
				(layer "Inner"
					(shape circle)
					(size 0.8001 0.8001)
					(clearance 0.1524)
				)
				(layer "B.Cu"
					(shape circle)
					(size 1.9939 1.9939)
					(clearance 0.10795)
				)
			)
		)
		(pad "4" thru_hole circle
			(at 0 2.54 90)
			(size 1.0033 1.0033)
			(drill 0.249936)
			(layers "*.Cu" "*.Mask")
			(remove_unused_layers no)
			(net "TDR_DIFF_85_TOP_DP")
			(clearance 0.10795)
			(thermal_gap 0.10795)
			(padstack
				(mode front_inner_back)
				(layer "Inner"
					(shape circle)
					(size 0.8001 0.8001)
					(clearance 0.1524)
				)
				(layer "B.Cu"
					(shape circle)
					(size 1.0033 1.0033)
					(clearance 0.10795)
				)
			)
		)
	)
	(footprint ""
		(layer "F.Cu")
		(at 35.980878 -17.623536 90)
		(property "Reference" "C56"
			(at 0 0 90)
			(layer "F.SilkS")
			(hide yes)
			(effects
				(font
					(size 1.27 1.27)
				)
			)
		)
		(property "Value" ""
			(at 0 0 90)
			(layer "F.Fab")
			(effects
				(font
					(size 1.27 1.27)
				)
			)
		)
		(duplicate_pad_numbers_are_jumpers no)
		(fp_line
			(start 0.299974 -0.150114)
			(end 0.299974 0.150114)
			(stroke
				(width 0.1)
				(type default)
			)
			(layer "F.Fab")
		)
		(fp_line
			(start -0.299974 -0.150114)
			(end 0.299974 -0.150114)
			(stroke
				(width 0.1)
				(type default)
			)
			(layer "F.Fab")
		)
		(fp_line
			(start 0.299974 0.150114)
			(end -0.299974 0.150114)
			(stroke
				(width 0.1)
				(type default)
			)
			(layer "F.Fab")
		)
		(fp_line
			(start -0.299974 0.150114)
			(end -0.299974 -0.150114)
			(stroke
				(width 0.1)
				(type default)
			)
			(layer "F.Fab")
		)
		(pad "1" smd rect
			(at -0.2667 0 90)
			(size 0.3048 0.381)
			(layers "F.Cu" "F.Mask" "F.Paste")
			(net "P5E_CPU1_G1_TX_C_DP<8>")
		)
		(pad "2" smd rect
			(at 0.2667 0 90)
			(size 0.3048 0.381)
			(layers "F.Cu" "F.Mask" "F.Paste")
			(net "P5E_CPU1_G1_TX_DP<8>")
		)
	)
	(footprint ""
		(layer "F.Cu")
		(at 68.212462 -39.421562)
		(property "Reference" "R3609"
			(at 0 0 0)
			(layer "F.SilkS")
			(hide yes)
			(effects
				(font
					(size 1.27 1.27)
				)
			)
		)
		(property "Value" ""
			(at 0 0 0)
			(layer "F.Fab")
			(effects
				(font
					(size 1.27 1.27)
				)
			)
		)
		(duplicate_pad_numbers_are_jumpers no)
		(fp_line
			(start -0.7874 -0.4064)
			(end 0.7874 -0.4064)
			(stroke
				(width 0.1524)
				(type default)
			)
			(layer "F.SilkS")
		)
		(fp_line
			(start -0.7874 0.4064)
			(end -0.7874 -0.4064)
			(stroke
				(width 0.1524)
				(type default)
			)
			(layer "F.SilkS")
		)
		(fp_line
			(start 0.7874 -0.4064)
			(end 0.7874 0.4064)
			(stroke
				(width 0.1524)
				(type default)
			)
			(layer "F.SilkS")
		)
		(fp_line
			(start 0.7874 0.4064)
			(end -0.7874 0.4064)
			(stroke
				(width 0.1524)
				(type default)
			)
			(layer "F.SilkS")
		)
		(fp_line
			(start -0.67945 -0.305054)
			(end -0.12065 -0.305054)
			(stroke
				(width 0.1)
				(type default)
			)
			(layer "F.Fab")
		)
		(fp_line
			(start -0.67945 0.3048)
			(end -0.67945 -0.305054)
			(stroke
				(width 0.1)
				(type default)
			)
			(layer "F.Fab")
		)
		(fp_line
			(start -0.12065 -0.305054)
			(end -0.12065 -0.2794)
			(stroke
				(width 0.1)
				(type default)
			)
			(layer "F.Fab")
		)
		(fp_line
			(start -0.12065 -0.2794)
			(end 0.12065 -0.2794)
			(stroke
				(width 0.1)
				(type default)
			)
			(layer "F.Fab")
		)
		(fp_line
			(start -0.12065 0.2794)
			(end -0.12065 0.3048)
			(stroke
				(width 0.1)
				(type default)
			)
			(layer "F.Fab")
		)
		(fp_line
			(start -0.12065 0.3048)
			(end -0.67945 0.3048)
			(stroke
				(width 0.1)
				(type default)
			)
			(layer "F.Fab")
		)
		(fp_line
			(start 0.120396 0.2794)
			(end -0.12065 0.2794)
			(stroke
				(width 0.1)
				(type default)
			)
			(layer "F.Fab")
		)
		(fp_line
			(start 0.120396 0.3048)
			(end 0.120396 0.2794)
			(stroke
				(width 0.1)
				(type default)
			)
			(layer "F.Fab")
		)
		(fp_line
			(start 0.12065 -0.3048)
			(end 0.67945 -0.3048)
			(stroke
				(width 0.1)
				(type default)
			)
			(layer "F.Fab")
		)
		(fp_line
			(start 0.12065 -0.2794)
			(end 0.12065 -0.3048)
			(stroke
				(width 0.1)
				(type default)
			)
			(layer "F.Fab")
		)
		(fp_line
			(start 0.67945 -0.3048)
			(end 0.67945 0.3048)
			(stroke
				(width 0.1)
				(type default)
			)
			(layer "F.Fab")
		)
		(fp_line
			(start 0.67945 0.3048)
			(end 0.120396 0.3048)
			(stroke
				(width 0.1)
				(type default)
			)
			(layer "F.Fab")
		)
		(pad "1" smd circle
			(at -0.40005 0)
			(size 0 0)
			(layers "F.Cu" "F.Mask" "F.Paste")
			(net "GND")
		)
		(pad "2" smd circle
			(at 0.40005 0)
			(size 0 0)
			(layers "F.Cu" "F.Mask" "F.Paste")
			(net "INA230_3_A0")
		)
	)
	(footprint ""
		(layer "F.Cu")
		(at 195.6943 -401.963382 90)
		(property "Reference" "PC1525"
			(at 0 0 90)
			(layer "F.SilkS")
			(hide yes)
			(effects
				(font
					(size 1.27 1.27)
				)
			)
		)
		(property "Value" ""
			(at 0 0 90)
			(layer "F.Fab")
			(effects
				(font
					(size 1.27 1.27)
				)
			)
		)
		(duplicate_pad_numbers_are_jumpers no)
		(fp_line
			(start 0.7874 -0.4064)
			(end 0.7874 0.4064)
			(stroke
				(width 0.1524)
				(type default)
			)
			(layer "F.SilkS")
		)
		(fp_line
			(start -0.7874 -0.4064)
			(end 0.7874 -0.4064)
			(stroke
				(width 0.1524)
				(type default)
			)
			(layer "F.SilkS")
		)
		(fp_line
			(start 0.7874 0.4064)
			(end -0.7874 0.4064)
			(stroke
				(width 0.1524)
				(type default)
			)
			(layer "F.SilkS")
		)
		(fp_line
			(start -0.7874 0.4064)
			(end -0.7874 -0.4064)
			(stroke
				(width 0.1524)
				(type default)
			)
			(layer "F.SilkS")
		)
		(fp_line
			(start -0.12065 -0.305054)
			(end -0.12065 -0.2794)
			(stroke
				(width 0.1)
				(type default)
			)
			(layer "F.Fab")
		)
		(fp_line
			(start -0.67945 -0.305054)
			(end -0.12065 -0.305054)
			(stroke
				(width 0.1)
				(type default)
			)
			(layer "F.Fab")
		)
		(fp_line
			(start 0.67945 -0.3048)
			(end 0.67945 0.3048)
			(stroke
				(width 0.1)
				(type default)
			)
			(layer "F.Fab")
		)
		(fp_line
			(start 0.12065 -0.3048)
			(end 0.67945 -0.3048)
			(stroke
				(width 0.1)
				(type default)
			)
			(layer "F.Fab")
		)
		(fp_line
			(start 0.12065 -0.2794)
			(end 0.12065 -0.3048)
			(stroke
				(width 0.1)
				(type default)
			)
			(layer "F.Fab")
		)
		(fp_line
			(start -0.12065 -0.2794)
			(end 0.12065 -0.2794)
			(stroke
				(width 0.1)
				(type default)
			)
			(layer "F.Fab")
		)
		(fp_line
			(start 0.120396 0.2794)
			(end -0.12065 0.2794)
			(stroke
				(width 0.1)
				(type default)
			)
			(layer "F.Fab")
		)
		(fp_line
			(start -0.12065 0.2794)
			(end -0.12065 0.3048)
			(stroke
				(width 0.1)
				(type default)
			)
			(layer "F.Fab")
		)
		(fp_line
			(start 0.67945 0.3048)
			(end 0.120396 0.3048)
			(stroke
				(width 0.1)
				(type default)
			)
			(layer "F.Fab")
		)
		(fp_line
			(start 0.120396 0.3048)
			(end 0.120396 0.2794)
			(stroke
				(width 0.1)
				(type default)
			)
			(layer "F.Fab")
		)
		(fp_line
			(start -0.12065 0.3048)
			(end -0.67945 0.3048)
			(stroke
				(width 0.1)
				(type default)
			)
			(layer "F.Fab")
		)
		(fp_line
			(start -0.67945 0.3048)
			(end -0.67945 -0.305054)
			(stroke
				(width 0.1)
				(type default)
			)
			(layer "F.Fab")
		)
		(pad "1" smd circle
			(at -0.40005 0 90)
			(size 0 0)
			(layers "F.Cu" "F.Mask" "F.Paste")
			(net "HSC_VDD_R_1")
		)
		(pad "2" smd circle
			(at 0.40005 0 90)
			(size 0 0)
			(layers "F.Cu" "F.Mask" "F.Paste")
			(net "AGND_HSC")
		)
	)
	(footprint ""
		(layer "F.Cu")
		(at 170.8404 -332.232508)
		(property "Reference" "PR288"
			(at 0 0 0)
			(layer "F.SilkS")
			(hide yes)
			(effects
				(font
					(size 1.27 1.27)
				)
			)
		)
		(property "Value" ""
			(at 0 0 0)
			(layer "F.Fab")
			(effects
				(font
					(size 1.27 1.27)
				)
			)
		)
		(duplicate_pad_numbers_are_jumpers no)
		(fp_line
			(start -0.7874 -0.4064)
			(end 0.7874 -0.4064)
			(stroke
				(width 0.1524)
				(type default)
			)
			(layer "F.SilkS")
		)
		(fp_line
			(start -0.7874 0.4064)
			(end -0.7874 -0.4064)
			(stroke
				(width 0.1524)
				(type default)
			)
			(layer "F.SilkS")
		)
		(fp_line
			(start 0.7874 -0.4064)
			(end 0.7874 0.4064)
			(stroke
				(width 0.1524)
				(type default)
			)
			(layer "F.SilkS")
		)
		(fp_line
			(start 0.7874 0.4064)
			(end -0.7874 0.4064)
			(stroke
				(width 0.1524)
				(type default)
			)
			(layer "F.SilkS")
		)
		(fp_line
			(start -0.67945 -0.305054)
			(end -0.12065 -0.305054)
			(stroke
				(width 0.1)
				(type default)
			)
			(layer "F.Fab")
		)
		(fp_line
			(start -0.67945 0.3048)
			(end -0.67945 -0.305054)
			(stroke
				(width 0.1)
				(type default)
			)
			(layer "F.Fab")
		)
		(fp_line
			(start -0.12065 -0.305054)
			(end -0.12065 -0.2794)
			(stroke
				(width 0.1)
				(type default)
			)
			(layer "F.Fab")
		)
		(fp_line
			(start -0.12065 -0.2794)
			(end 0.12065 -0.2794)
			(stroke
				(width 0.1)
				(type default)
			)
			(layer "F.Fab")
		)
		(fp_line
			(start -0.12065 0.2794)
			(end -0.12065 0.3048)
			(stroke
				(width 0.1)
				(type default)
			)
			(layer "F.Fab")
		)
		(fp_line
			(start -0.12065 0.3048)
			(end -0.67945 0.3048)
			(stroke
				(width 0.1)
				(type default)
			)
			(layer "F.Fab")
		)
		(fp_line
			(start 0.120396 0.2794)
			(end -0.12065 0.2794)
			(stroke
				(width 0.1)
				(type default)
			)
			(layer "F.Fab")
		)
		(fp_line
			(start 0.120396 0.3048)
			(end 0.120396 0.2794)
			(stroke
				(width 0.1)
				(type default)
			)
			(layer "F.Fab")
		)
		(fp_line
			(start 0.12065 -0.3048)
			(end 0.67945 -0.3048)
			(stroke
				(width 0.1)
				(type default)
			)
			(layer "F.Fab")
		)
		(fp_line
			(start 0.12065 -0.2794)
			(end 0.12065 -0.3048)
			(stroke
				(width 0.1)
				(type default)
			)
			(layer "F.Fab")
		)
		(fp_line
			(start 0.67945 -0.3048)
			(end 0.67945 0.3048)
			(stroke
				(width 0.1)
				(type default)
			)
			(layer "F.Fab")
		)
		(fp_line
			(start 0.67945 0.3048)
			(end 0.120396 0.3048)
			(stroke
				(width 0.1)
				(type default)
			)
			(layer "F.Fab")
		)
		(pad "1" smd circle
			(at -0.40005 0)
			(size 0 0)
			(layers "F.Cu" "F.Mask" "F.Paste")
			(net "VSENSE_VSS_SENSE_C_P1")
		)
		(pad "2" smd circle
			(at 0.40005 0)
			(size 0 0)
			(layers "F.Cu" "F.Mask" "F.Paste")
			(net "GND")
		)
	)
	(footprint ""
		(layer "F.Cu")
		(at 69.6976 -389.95858)
		(property "Reference" "R1389"
			(at 0 0 0)
			(layer "F.SilkS")
			(hide yes)
			(effects
				(font
					(size 1.27 1.27)
				)
			)
		)
		(property "Value" ""
			(at 0 0 0)
			(layer "F.Fab")
			(effects
				(font
					(size 1.27 1.27)
				)
			)
		)
		(duplicate_pad_numbers_are_jumpers no)
		(fp_line
			(start -0.32512 -0.175006)
			(end 0.32512 -0.175006)
			(stroke
				(width 0.1)
				(type default)
			)
			(layer "F.Fab")
		)
		(fp_line
			(start -0.32512 0.175006)
			(end -0.32512 -0.175006)
			(stroke
				(width 0.1)
				(type default)
			)
			(layer "F.Fab")
		)
		(fp_line
			(start 0.32512 -0.175006)
			(end 0.32512 0.175006)
			(stroke
				(width 0.1)
				(type default)
			)
			(layer "F.Fab")
		)
		(fp_line
			(start 0.32512 0.175006)
			(end -0.32512 0.175006)
			(stroke
				(width 0.1)
				(type default)
			)
			(layer "F.Fab")
		)
		(pad "1" smd rect
			(at -0.2667 0)
			(size 0.3048 0.381)
			(layers "F.Cu" "F.Mask" "F.Paste")
			(net "RXDET_BYP_RT_CPU1_P0")
		)
		(pad "2" smd rect
			(at 0.2667 0 180)
			(size 0.3048 0.381)
			(layers "F.Cu" "F.Mask" "F.Paste")
			(net "GND")
		)
	)
)
